# T6G (Grand Teton) — schematic netlist excerpt (pin names and nets, part order shuffled) for the footprints in the layout excerpt that follows; sources: Cadence DE-HDL packaged netlist, KiCad conversion of 04192023_DAF0TMB3IC0_F0TG_MB_C_brd_V02_OCP.brd

PR3922  Q_RES  0 5% CHIP  pkg 0402LF  page 263 : A = HSC_FLT_TYPE_2 ; B = HSC_FLT_TYPE
C6000  Q_CAP  0.1UF 25V 10% X7R  pkg 0402  page 150 : A = SCM_VDD_RTC ; B = GND

(kicad_pcb
	(version 20260206)
	(generator "pcbnew")
	(generator_version "10.0")
	(general
		(thickness 1.6)
		(legacy_teardrops no)
	)
	(paper "A4")
	(title_block
		(title "04192023_DAF0TMB3IC0_F0TG_MB_C_brd_V02_OCP.brd")
		(comment 1 "Grand Teton / footprints 4486-4487 of 8354")
	)
	(layers
		(0 "F.Cu" signal "TOP")
		(4 "In1.Cu" signal "GND")
		(6 "In2.Cu" signal "IN1")
		(8 "In3.Cu" signal "GND1")
		(10 "In4.Cu" signal "IN2")
		(12 "In5.Cu" signal "GND2")
		(14 "In6.Cu" signal "IN3")
		(16 "In7.Cu" signal "GND3")
		(18 "In8.Cu" signal "VCC")
		(20 "In9.Cu" signal "VCC1")
		(22 "In10.Cu" signal "GND4")
		(24 "In11.Cu" signal "IN4")
		(26 "In12.Cu" signal "GND5")
		(28 "In13.Cu" signal "IN5")
		(30 "In14.Cu" signal "GND6")
		(32 "In15.Cu" signal "IN6")
		(34 "In16.Cu" signal "GND7")
		(2 "B.Cu" signal "BOTTOM")
		(9 "F.Adhes" user "F.Adhesive")
		(11 "B.Adhes" user "B.Adhesive")
		(13 "F.Paste" user "Package Geometry/Pastemask Top")
		(15 "B.Paste" user "Package Geometry/Pastemask Bottom")
		(5 "F.SilkS" user "Ref Des/Silkscreen Top")
		(7 "B.SilkS" user "Ref Des/Silkscreen Bottom")
		(1 "F.Mask" user "Board Geometry/Soldermask Top")
		(3 "B.Mask" user "Board Geometry/Soldermask Bottom")
		(17 "Dwgs.User" user "User.Drawings")
		(19 "Cmts.User" user "User.Comments")
		(21 "Eco1.User" user "User.Eco1")
		(23 "Eco2.User" user "User.Eco2")
		(25 "Edge.Cuts" user "Board Geometry/Outline")
		(27 "Margin" user)
		(31 "F.CrtYd" user "Package Geometry/Place Bound Top")
		(29 "B.CrtYd" user "Package Geometry/Place Bound Bottom")
		(35 "F.Fab" user "Ref Des/Assembly Top")
		(33 "B.Fab" user "Ref Des/Assembly Bottom")
	)
	(footprint ""
		(layer "F.Cu")
		(at 215.4301 -406.052782)
		(property "Reference" "PR3922"
			(at 0 0 0)
			(layer "F.SilkS")
			(hide yes)
			(effects
				(font
					(size 1.27 1.27)
				)
			)
		)
		(property "Value" ""
			(at 0 0 0)
			(layer "F.Fab")
			(effects
				(font
					(size 1.27 1.27)
				)
			)
		)
		(duplicate_pad_numbers_are_jumpers no)
		(fp_line
			(start -0.7874 -0.4064)
			(end 0.7874 -0.4064)
			(stroke
				(width 0.1524)
				(type default)
			)
			(layer "F.SilkS")
		)
		(fp_line
			(start -0.7874 0.4064)
			(end -0.7874 -0.4064)
			(stroke
				(width 0.1524)
				(type default)
			)
			(layer "F.SilkS")
		)
		(fp_line
			(start 0.7874 -0.4064)
			(end 0.7874 0.4064)
			(stroke
				(width 0.1524)
				(type default)
			)
			(layer "F.SilkS")
		)
		(fp_line
			(start 0.7874 0.4064)
			(end -0.7874 0.4064)
			(stroke
				(width 0.1524)
				(type default)
			)
			(layer "F.SilkS")
		)
		(fp_line
			(start -0.67945 -0.305054)
			(end -0.12065 -0.305054)
			(stroke
				(width 0.1)
				(type default)
			)
			(layer "F.Fab")
		)
		(fp_line
			(start -0.67945 0.3048)
			(end -0.67945 -0.305054)
			(stroke
				(width 0.1)
				(type default)
			)
			(layer "F.Fab")
		)
		(fp_line
			(start -0.12065 -0.305054)
			(end -0.12065 -0.2794)
			(stroke
				(width 0.1)
				(type default)
			)
			(layer "F.Fab")
		)
		(fp_line
			(start -0.12065 -0.2794)
			(end 0.12065 -0.2794)
			(stroke
				(width 0.1)
				(type default)
			)
			(layer "F.Fab")
		)
		(fp_line
			(start -0.12065 0.2794)
			(end -0.12065 0.3048)
			(stroke
				(width 0.1)
				(type default)
			)
			(layer "F.Fab")
		)
		(fp_line
			(start -0.12065 0.3048)
			(end -0.67945 0.3048)
			(stroke
				(width 0.1)
				(type default)
			)
			(layer "F.Fab")
		)
		(fp_line
			(start 0.120396 0.2794)
			(end -0.12065 0.2794)
			(stroke
				(width 0.1)
				(type default)
			)
			(layer "F.Fab")
		)
		(fp_line
			(start 0.120396 0.3048)
			(end 0.120396 0.2794)
			(stroke
				(width 0.1)
				(type default)
			)
			(layer "F.Fab")
		)
		(fp_line
			(start 0.12065 -0.3048)
			(end 0.67945 -0.3048)
			(stroke
				(width 0.1)
				(type default)
			)
			(layer "F.Fab")
		)
		(fp_line
			(start 0.12065 -0.2794)
			(end 0.12065 -0.3048)
			(stroke
				(width 0.1)
				(type default)
			)
			(layer "F.Fab")
		)
		(fp_line
			(start 0.67945 -0.3048)
			(end 0.67945 0.3048)
			(stroke
				(width 0.1)
				(type default)
			)
			(layer "F.Fab")
		)
		(fp_line
			(start 0.67945 0.3048)
			(end 0.120396 0.3048)
			(stroke
				(width 0.1)
				(type default)
			)
			(layer "F.Fab")
		)
		(pad "1" smd circle
			(at -0.40005 0)
			(size 0 0)
			(layers "F.Cu" "F.Mask" "F.Paste")
			(net "HSC_FLT_TYPE_2")
		)
		(pad "2" smd circle
			(at 0.40005 0)
			(size 0 0)
			(layers "F.Cu" "F.Mask" "F.Paste")
			(net "HSC_FLT_TYPE")
		)
	)
	(footprint ""
		(layer "F.Cu")
		(at 147.877022 -23.284942 90)
		(property "Reference" "C6000"
			(at 0 0 90)
			(layer "F.SilkS")
			(hide yes)
			(effects
				(font
					(size 1.27 1.27)
				)
			)
		)
		(property "Value" ""
			(at 0 0 90)
			(layer "F.Fab")
			(effects
				(font
					(size 1.27 1.27)
				)
			)
		)
		(duplicate_pad_numbers_are_jumpers no)
		(fp_line
			(start 0.7874 -0.4064)
			(end 0.7874 0.4064)
			(stroke
				(width 0.1524)
				(type default)
			)
			(layer "F.SilkS")
		)
		(fp_line
			(start -0.7874 -0.4064)
			(end 0.7874 -0.4064)
			(stroke
				(width 0.1524)
				(type default)
			)
			(layer "F.SilkS")
		)
		(fp_line
			(start 0.7874 0.4064)
			(end -0.7874 0.4064)
			(stroke
				(width 0.1524)
				(type default)
			)
			(layer "F.SilkS")
		)
		(fp_line
			(start -0.7874 0.4064)
			(end -0.7874 -0.4064)
			(stroke
				(width 0.1524)
				(type default)
			)
			(layer "F.SilkS")
		)
		(fp_line
			(start -0.12065 -0.305054)
			(end -0.12065 -0.2794)
			(stroke
				(width 0.1)
				(type default)
			)
			(layer "F.Fab")
		)
		(fp_line
			(start -0.67945 -0.305054)
			(end -0.12065 -0.305054)
			(stroke
				(width 0.1)
				(type default)
			)
			(layer "F.Fab")
		)
		(fp_line
			(start 0.67945 -0.3048)
			(end 0.67945 0.3048)
			(stroke
				(width 0.1)
				(type default)
			)
			(layer "F.Fab")
		)
		(fp_line
			(start 0.12065 -0.3048)
			(end 0.67945 -0.3048)
			(stroke
				(width 0.1)
				(type default)
			)
			(layer "F.Fab")
		)
		(fp_line
			(start 0.12065 -0.2794)
			(end 0.12065 -0.3048)
			(stroke
				(width 0.1)
				(type default)
			)
			(layer "F.Fab")
		)
		(fp_line
			(start -0.12065 -0.2794)
			(end 0.12065 -0.2794)
			(stroke
				(width 0.1)
				(type default)
			)
			(layer "F.Fab")
		)
		(fp_line
			(start 0.120396 0.2794)
			(end -0.12065 0.2794)
			(stroke
				(width 0.1)
				(type default)
			)
			(layer "F.Fab")
		)
		(fp_line
			(start -0.12065 0.2794)
			(end -0.12065 0.3048)
			(stroke
				(width 0.1)
				(type default)
			)
			(layer "F.Fab")
		)
		(fp_line
			(start 0.67945 0.3048)
			(end 0.120396 0.3048)
			(stroke
				(width 0.1)
				(type default)
			)
			(layer "F.Fab")
		)
		(fp_line
			(start 0.120396 0.3048)
			(end 0.120396 0.2794)
			(stroke
				(width 0.1)
				(type default)
			)
			(layer "F.Fab")
		)
		(fp_line
			(start -0.12065 0.3048)
			(end -0.67945 0.3048)
			(stroke
				(width 0.1)
				(type default)
			)
			(layer "F.Fab")
		)
		(fp_line
			(start -0.67945 0.3048)
			(end -0.67945 -0.305054)
			(stroke
				(width 0.1)
				(type default)
			)
			(layer "F.Fab")
		)
		(pad "1" smd circle
			(at -0.40005 0 90)
			(size 0 0)
			(layers "F.Cu" "F.Mask" "F.Paste")
			(net "SCM_VDD_RTC")
		)
		(pad "2" smd circle
			(at 0.40005 0 90)
			(size 0 0)
			(layers "F.Cu" "F.Mask" "F.Paste")
			(net "GND")
		)
	)
)
